G04 ================== begin FILE IDENTIFICATION RECORD ==================*
G04 Layout Name:  13919-sa.brd*
G04 Film Name:    L4*
G04 File Format:  Gerber RS274X*
G04 File Origin:  Cadence Allegro 16.5-S039*
G04 Origin Date:  Fri Nov 22 15:27:06 2013*
G04 *
G04 Layer:  VIA CLASS/BOTTOM*
G04 Layer:  PIN/BOTTOM*
G04 Layer:  ETCH/BOTTOM*
G04 Layer:  DRAWING FORMAT/LAYER_L4*
G04 Layer:  DRAWING FORMAT/LAYER_PCB_STORY*
G04 *
G04 Offset:    (0.00 0.00)*
G04 Mirror:    No*
G04 Mode:      Positive*
G04 Rotation:  0*
G04 FullContactRelief:  No*
G04 UndefLineWidth:     6.00*
G04 ================== end FILE IDENTIFICATION RECORD ====================*
%FSLAX35Y35*MOIN*%
%IR0*IPPOS*OFA0.00000B0.00000*MIA0B0*SFA1.00000B1.00000*%
%ADD14C,.01*%
%ADD12C,.022*%
%ADD11R,.028X.126*%
%ADD15C,.043*%
%ADD10R,.028X.165*%
%ADD13C,.028*%
%ADD16C,.02*%
%ADD17C,.025*%
%ADD18C,.005*%
%ADD19C,.006*%
%ADD20C,.0055*%
%ADD21C,.00425*%
%ADD22C,.06704*%
G75*
%LPD*%
G75*
G36*
G01X29540Y68272D02*
G03X31132Y62219I1958J-2721D01*
G01X31202Y62211D01*
X33306Y60106D01*
Y59728D01*
X35983Y57052D01*
Y44113D01*
X26730Y34860D01*
X21999D01*
G03X21199Y35538I-4873J-4939D01*
G01X21186Y35547D01*
X11321Y45412D01*
G02X11411Y46045I283J283D01*
G03X10181Y56172I-2661J4815D01*
G01X10033Y56212D01*
Y67100D01*
X12333Y69400D01*
Y73386D01*
G02X12976Y73703I400J0D01*
G03X22031Y80362I3562J4643D01*
G02X22407Y80900I376J138D01*
G01X25184D01*
G03X28910Y80199I2374J2366D01*
G01X29036Y80254D01*
X29540Y79750D01*
Y76828D01*
G02X28971Y76465I-400J0D01*
G03Y70387I-1413J-3039D01*
G02X29540Y70024I169J-363D01*
G01Y68272D01*
G37*
G36*
G01X367237Y92096D02*
X368433Y90900D01*
Y68690D01*
X366753Y67010D01*
X353950D01*
X349870Y62930D01*
Y30190D01*
X349954Y30106D01*
X349952Y30022D01*
G03Y29921I6938J-51D01*
G01Y24800D01*
X342933D01*
X341433Y26300D01*
Y34230D01*
X336833Y38830D01*
Y62050D01*
G02X337377Y62424I400J1D01*
G03Y68678I1206J3127D01*
G02X336833Y69052I-144J373D01*
G01Y70884D01*
G03Y75968I-2185J2542D01*
G01Y80724D01*
G03Y85808I-2185J2542D01*
G01Y87640D01*
G02X337377Y88014I400J1D01*
G03X338312Y94482I1206J3127D01*
G02X337996Y95163I-33J399D01*
G01X338633Y95800D01*
X359179D01*
X359216Y95646D01*
G03X367107Y92028I5354J1264D01*
G01X367237Y92096D01*
G37*
%LPC*%
G75*
G54D22*
X23623Y65551D03*
X350393Y73426D03*
X346458Y65551D03*
X342518Y73426D03*
X350393Y83266D03*
X346458Y91141D03*
X342518Y83266D03*
%LPD*%
G75*
G54D10*
X23622Y13762D03*
X31496D03*
X35433D03*
X39370D03*
X43307D03*
X47244D03*
X51181D03*
X55118D03*
X59055D03*
X62992D03*
X66929D03*
X70866D03*
X74803D03*
X78740D03*
X82677D03*
X86614D03*
X90551D03*
X94488D03*
X98425D03*
X102362D03*
X106299D03*
X110236D03*
X114173D03*
X118110D03*
X122047D03*
X125984D03*
X129921D03*
X133858D03*
X137795D03*
X141732D03*
X145669D03*
X149606D03*
X153543D03*
X161417D03*
X165354D03*
X169291D03*
X173228D03*
X177165D03*
X181102D03*
X185039D03*
X188976D03*
X192913D03*
X196850D03*
X200787D03*
X204724D03*
X208661D03*
X212598D03*
X216535D03*
X220472D03*
X228346D03*
X232283D03*
X236220D03*
X240157D03*
X244094D03*
X248031D03*
X251968D03*
X255905D03*
X259842D03*
X263779D03*
X267716D03*
X271653D03*
X275590D03*
X283464D03*
X287401D03*
X291338D03*
X311024D03*
X314961D03*
X318898D03*
X322835D03*
X326772D03*
X330709D03*
X334646D03*
X338583D03*
X342520D03*
X346457D03*
X350394D03*
X295275D03*
X299212D03*
G54D20*
G01X47243Y91141D02*
X47247D01*
X47983Y90405D01*
Y87400D01*
X46783Y86200D01*
Y70900D01*
X50533Y67150D01*
Y62000D01*
X48538Y60005D01*
Y23920D01*
X47244Y22626D01*
Y12262D01*
G01X35433Y83266D02*
X35432D01*
Y85801D01*
X34633Y86600D01*
X33343D01*
X32383Y85640D01*
Y71350D01*
X36133Y67600D01*
Y60900D01*
X39583Y57450D01*
Y36220D01*
X36133Y32770D01*
Y27494D01*
X34139Y25500D01*
Y23920D01*
X35433Y22626D01*
Y12262D01*
G01X31498Y91141D02*
X31497D01*
X32233Y90405D01*
Y87400D01*
X31033Y86200D01*
Y70790D01*
X34783Y67040D01*
Y60340D01*
X38233Y56890D01*
Y36780D01*
X34783Y33330D01*
Y28054D01*
X32789Y26060D01*
Y23920D01*
X31496Y22627D01*
Y12262D01*
G01X98428Y83266D02*
X98417D01*
Y85801D01*
X97618Y86600D01*
X96328D01*
X95368Y85640D01*
Y71460D01*
X99118Y67710D01*
Y62518D01*
X95070Y58470D01*
Y57478D01*
X95620Y56928D01*
X97854D01*
X99194Y55588D01*
Y53368D01*
X97854Y52028D01*
X95620D01*
X95070Y51478D01*
Y50378D01*
X95620Y49828D01*
X97854D01*
X99194Y48488D01*
Y46268D01*
X97854Y44928D01*
X95620D01*
X95070Y44378D01*
Y43278D01*
X95620Y42728D01*
X97854D01*
X99194Y41388D01*
Y39168D01*
X97854Y37828D01*
X97682D01*
X97132Y37278D01*
Y23920D01*
X98425Y22627D01*
Y12262D01*
G01X94488Y91141D02*
X94482D01*
X95218Y90405D01*
Y87400D01*
X94018Y86200D01*
Y70900D01*
X97768Y67150D01*
Y63078D01*
X93720Y59030D01*
Y56918D01*
X95060Y55578D01*
X97294D01*
X97844Y55028D01*
Y53928D01*
X97294Y53378D01*
X95060D01*
X93720Y52038D01*
Y49818D01*
X95060Y48478D01*
X97294D01*
X97844Y47928D01*
Y46828D01*
X97294Y46278D01*
X95060D01*
X93720Y44938D01*
Y42718D01*
X95060Y41378D01*
X97294D01*
X97844Y40828D01*
Y39728D01*
X97294Y39178D01*
X97122D01*
X95782Y37838D01*
Y23920D01*
X94488Y22626D01*
Y12262D01*
G01X82678Y83266D02*
X82672D01*
Y85801D01*
X81873Y86600D01*
X80583D01*
X79623Y85640D01*
Y71460D01*
X83373Y67710D01*
Y59329D01*
X81384Y57340D01*
Y23920D01*
X82677Y22627D01*
Y12262D01*
G01X78743Y91141D02*
X79473Y90411D01*
Y87400D01*
X78273Y86200D01*
Y70900D01*
X82023Y67150D01*
Y59889D01*
X80034Y57900D01*
Y23920D01*
X78740Y22626D01*
Y12262D01*
G01X66928Y83266D02*
X66927D01*
Y85801D01*
X66128Y86600D01*
X64838D01*
X63878Y85640D01*
Y71460D01*
X67628Y67710D01*
Y61495D01*
X65636Y59503D01*
Y23920D01*
X66929Y22627D01*
Y12262D01*
G01X62993Y91141D02*
Y91140D01*
X63728Y90405D01*
Y87400D01*
X62528Y86200D01*
Y70900D01*
X66278Y67150D01*
Y62055D01*
X64286Y60063D01*
Y23920D01*
X62992Y22626D01*
Y12262D01*
G01X51183Y83266D02*
X51182D01*
Y85801D01*
X50383Y86600D01*
X49093D01*
X48133Y85640D01*
Y71460D01*
X51883Y67710D01*
Y61440D01*
X49888Y59445D01*
Y23920D01*
X51181Y22627D01*
Y12262D01*
G01X161418Y83266D02*
X161417D01*
X161397Y83286D01*
Y83936D01*
X159933Y85400D01*
X159033D01*
X158348Y84715D01*
Y71460D01*
X162098Y67710D01*
Y59165D01*
X159883Y56950D01*
Y24050D01*
X161417Y22516D01*
Y12262D01*
G01X157483Y91141D02*
Y91140D01*
X159463Y89160D01*
Y87740D01*
X156998Y85275D01*
Y70900D01*
X160748Y67150D01*
Y59725D01*
X158533Y57510D01*
Y24000D01*
X157480Y22947D01*
Y15712D01*
G01X145668Y83266D02*
X145652D01*
Y85801D01*
X144853Y86600D01*
X143563D01*
X142603Y85640D01*
Y71460D01*
X146353Y67710D01*
Y62143D01*
X142290Y58080D01*
Y57103D01*
X142840Y56553D01*
X145122D01*
X146462Y55213D01*
Y52993D01*
X145122Y51653D01*
X142840D01*
X142290Y51103D01*
Y50003D01*
X142840Y49453D01*
X145122D01*
X146462Y48113D01*
Y45893D01*
X145122Y44553D01*
X142840D01*
X142290Y44003D01*
Y42903D01*
X142840Y42353D01*
X145122D01*
X146462Y41013D01*
Y38793D01*
X145122Y37453D01*
X144926D01*
X144376Y36903D01*
Y23920D01*
X145669Y22627D01*
Y12262D01*
G01X141733Y91141D02*
X142453Y90421D01*
Y87400D01*
X141253Y86200D01*
Y70900D01*
X145003Y67150D01*
Y62703D01*
X140940Y58640D01*
Y56543D01*
X142280Y55203D01*
X144562D01*
X145112Y54653D01*
Y53553D01*
X144562Y53003D01*
X142280D01*
X140940Y51663D01*
Y49443D01*
X142280Y48103D01*
X144562D01*
X145112Y47553D01*
Y46453D01*
X144562Y45903D01*
X142280D01*
X140940Y44563D01*
Y42343D01*
X142280Y41003D01*
X144562D01*
X145112Y40453D01*
Y39353D01*
X144562Y38803D01*
X144366D01*
X143026Y37463D01*
Y23920D01*
X141732Y22626D01*
Y12262D01*
G01X129923Y83266D02*
X129907D01*
Y85801D01*
X129108Y86600D01*
X127818D01*
X126858Y85640D01*
Y71460D01*
X130608Y67710D01*
Y62288D01*
X126530Y58210D01*
Y57248D01*
X127080Y56698D01*
X129386D01*
X130726Y55358D01*
Y53138D01*
X129386Y51798D01*
X127080D01*
X126530Y51248D01*
Y50148D01*
X127080Y49598D01*
X129386D01*
X130726Y48258D01*
Y46038D01*
X129386Y44698D01*
X127080D01*
X126530Y44148D01*
Y43048D01*
X127080Y42498D01*
X129386D01*
X130726Y41158D01*
Y38938D01*
X129386Y37598D01*
X129178D01*
X128628Y37048D01*
Y23920D01*
X129921Y22627D01*
Y12262D01*
G01X125983Y91141D02*
X125972D01*
X126708Y90405D01*
Y87400D01*
X125508Y86200D01*
Y70900D01*
X129258Y67150D01*
Y62848D01*
X125180Y58770D01*
Y56688D01*
X126520Y55348D01*
X128826D01*
X129376Y54798D01*
Y53698D01*
X128826Y53148D01*
X126520D01*
X125180Y51808D01*
Y49588D01*
X126520Y48248D01*
X128826D01*
X129376Y47698D01*
Y46598D01*
X128826Y46048D01*
X126520D01*
X125180Y44708D01*
Y42488D01*
X126520Y41148D01*
X128826D01*
X129376Y40598D01*
Y39498D01*
X128826Y38948D01*
X128618D01*
X127278Y37608D01*
Y23920D01*
X125984Y22626D01*
Y12262D01*
G01X114173Y83266D02*
X114162D01*
Y85801D01*
X113363Y86600D01*
X112073D01*
X111113Y85640D01*
Y71460D01*
X114863Y67710D01*
Y61593D01*
X110830Y57560D01*
Y56473D01*
X111380Y55923D01*
X113590D01*
X114930Y54583D01*
Y52363D01*
X113590Y51023D01*
X111380D01*
X110830Y50473D01*
Y49373D01*
X111380Y48823D01*
X113590D01*
X114930Y47483D01*
Y45263D01*
X113590Y43923D01*
X111380D01*
X110830Y43373D01*
Y42273D01*
X111380Y41723D01*
X113590D01*
X114930Y40383D01*
Y38163D01*
X113590Y36823D01*
X113430D01*
X112880Y36273D01*
Y23920D01*
X114173Y22627D01*
Y12262D01*
G01X110238Y91141D02*
X110227D01*
X110963Y90405D01*
Y87400D01*
X109763Y86200D01*
Y70900D01*
X113513Y67150D01*
Y62153D01*
X109480Y58120D01*
Y55913D01*
X110820Y54573D01*
X113030D01*
X113580Y54023D01*
Y52923D01*
X113030Y52373D01*
X110820D01*
X109480Y51033D01*
Y48813D01*
X110820Y47473D01*
X113030D01*
X113580Y46923D01*
Y45823D01*
X113030Y45273D01*
X110820D01*
X109480Y43933D01*
Y41713D01*
X110820Y40373D01*
X113030D01*
X113580Y39823D01*
Y38723D01*
X113030Y38173D01*
X112870D01*
X111530Y36833D01*
Y23920D01*
X110236Y22626D01*
Y12262D01*
G01X208663Y83266D02*
X208632D01*
Y85801D01*
X207833Y86600D01*
X206543D01*
X205583Y85640D01*
Y71460D01*
X209333Y67710D01*
Y58005D01*
X207368Y56040D01*
Y23920D01*
X208661Y22627D01*
Y12262D01*
G01X204723Y91141D02*
X205433Y90431D01*
Y87400D01*
X204233Y86200D01*
Y70900D01*
X207983Y67150D01*
Y58565D01*
X206018Y56600D01*
Y23920D01*
X204724Y22626D01*
Y12262D01*
G01X224408Y83266D02*
X224407D01*
X224833Y83692D01*
Y86800D01*
X223933Y87700D01*
X222133D01*
X221328Y86895D01*
Y71460D01*
X225078Y67710D01*
Y57735D01*
X223083Y55740D01*
Y23950D01*
X224409Y22624D01*
Y15712D01*
G01X220473Y91141D02*
X220471Y91140D01*
X220442Y91111D01*
Y87919D01*
X219978Y87455D01*
Y70900D01*
X223728Y67150D01*
Y58295D01*
X221733Y56300D01*
Y23700D01*
X220472Y22439D01*
Y12262D01*
G01X287403Y83266D02*
X287402D01*
Y85431D01*
X286233Y86600D01*
X285143D01*
X284083Y85540D01*
Y79653D01*
X282080Y77650D01*
X278560D01*
X276300Y75390D01*
Y71690D01*
X280233Y67757D01*
Y63000D01*
X277445Y60212D01*
Y40585D01*
X274570Y37710D01*
Y36680D01*
X275210Y36040D01*
X284300D01*
X286108Y34232D01*
Y23920D01*
X287401Y22627D01*
Y12262D01*
G01X283463Y91141D02*
Y91140D01*
X284033Y90570D01*
Y87400D01*
X282733Y86100D01*
Y80213D01*
X281520Y79000D01*
X278000D01*
X274950Y75950D01*
Y71130D01*
X278883Y67197D01*
Y63560D01*
X276095Y60772D01*
Y41145D01*
X273220Y38270D01*
Y36120D01*
X274650Y34690D01*
X283740D01*
X284758Y33672D01*
Y23920D01*
X283464Y22626D01*
Y12262D01*
G01X271653Y83266D02*
X271612D01*
Y85801D01*
X270813Y86600D01*
X269523D01*
X268563Y85640D01*
Y81470D01*
X265083Y77990D01*
X263370D01*
X260473Y75093D01*
Y70930D01*
X256883Y67340D01*
Y63340D01*
X252783Y59240D01*
Y41550D01*
X258413Y35920D01*
X266023D01*
X270359Y31584D01*
Y23920D01*
X271653Y22626D01*
Y12262D01*
G01X267718Y91141D02*
X267677D01*
X268413Y90405D01*
Y87400D01*
X267213Y86200D01*
Y82030D01*
X264523Y79340D01*
X262810D01*
X259123Y75653D01*
Y71490D01*
X255533Y67900D01*
Y63900D01*
X251433Y59800D01*
Y40990D01*
X257853Y34570D01*
X265463D01*
X269009Y31024D01*
Y23920D01*
X267716Y22627D01*
Y12262D01*
G01X255908Y83266D02*
X255867D01*
Y85801D01*
X255068Y86600D01*
X253778D01*
X252818Y85640D01*
Y71575D01*
X248683Y67440D01*
Y57168D01*
X247343Y55828D01*
X245490D01*
X244990Y55328D01*
Y54128D01*
X245490Y53628D01*
X247343D01*
X248683Y52288D01*
Y50068D01*
X247343Y48728D01*
X245640D01*
X245090Y48178D01*
Y47078D01*
X245640Y46528D01*
X247343D01*
X248683Y45188D01*
Y42968D01*
X247343Y41628D01*
X245640D01*
X245090Y41078D01*
Y39978D01*
X245640Y39428D01*
X247343D01*
X254611Y32160D01*
Y23920D01*
X255905Y22626D01*
Y12262D01*
G01X251968Y91141D02*
X251932D01*
X252668Y90405D01*
Y87400D01*
X251468Y86200D01*
Y72135D01*
X247333Y68000D01*
Y57728D01*
X246783Y57178D01*
X244930D01*
X243640Y55888D01*
Y53568D01*
X244930Y52278D01*
X246783D01*
X247333Y51728D01*
Y50628D01*
X246783Y50078D01*
X245080D01*
X243740Y48738D01*
Y46518D01*
X245080Y45178D01*
X246783D01*
X247333Y44628D01*
Y43528D01*
X246783Y42978D01*
X245080D01*
X243740Y41638D01*
Y39418D01*
X245080Y38078D01*
X246783D01*
X253261Y31600D01*
Y23920D01*
X251968Y22627D01*
Y12262D01*
G01X240158Y83266D02*
X240122D01*
Y85801D01*
X239323Y86600D01*
X238033D01*
X237073Y85640D01*
Y71460D01*
X240823Y67710D01*
Y58980D01*
X237523Y55680D01*
X235680D01*
X235180Y55180D01*
Y53980D01*
X235680Y53480D01*
X237523D01*
X238863Y52140D01*
Y49920D01*
X237523Y48580D01*
X235480D01*
X234930Y48030D01*
Y46930D01*
X235480Y46380D01*
X237523D01*
X238863Y45040D01*
Y42820D01*
X237523Y41480D01*
X235480D01*
X234930Y40930D01*
Y39830D01*
X235480Y39280D01*
X237523D01*
X238863Y37940D01*
Y23920D01*
X240157Y22626D01*
Y12262D01*
G01X236223Y91141D02*
X236923Y90441D01*
Y87400D01*
X235723Y86200D01*
Y70900D01*
X239473Y67150D01*
Y59540D01*
X236963Y57030D01*
X235120D01*
X233830Y55740D01*
Y53420D01*
X235120Y52130D01*
X236963D01*
X237513Y51580D01*
Y50480D01*
X236963Y49930D01*
X234920D01*
X233580Y48590D01*
Y46370D01*
X234920Y45030D01*
X236963D01*
X237513Y44480D01*
Y43380D01*
X236963Y42830D01*
X234920D01*
X233580Y41490D01*
Y39270D01*
X234920Y37930D01*
X236963D01*
X237513Y37380D01*
Y23920D01*
X236220Y22627D01*
Y12262D01*
G01X318898Y83266D02*
X318897D01*
Y86036D01*
X318072Y86861D01*
X317294D01*
X317283Y86850D01*
Y86840D01*
X315683Y85240D01*
Y71450D01*
X305333Y61100D01*
Y41700D01*
X308933Y38100D01*
X312803D01*
X317604Y33299D01*
Y23920D01*
X318898Y22626D01*
Y12262D01*
G01X314963Y91141D02*
Y91140D01*
X316073Y90030D01*
Y87540D01*
X314333Y85800D01*
Y72010D01*
X303983Y61660D01*
Y41140D01*
X308373Y36750D01*
X312243D01*
X316254Y32739D01*
Y23920D01*
X314961Y22627D01*
Y12262D01*
G54D11*
X27559Y15712D03*
X157480D03*
X224409D03*
X279527D03*
G54D21*
G01X192913Y83266D02*
X192912D01*
X189933Y80287D01*
Y71300D01*
X193633Y67600D01*
Y59420D01*
X192913Y58700D01*
Y12262D01*
G01X177168Y83266D02*
X177167D01*
X174093Y80192D01*
Y71460D01*
X177843Y67710D01*
Y59000D01*
X175872Y57029D01*
Y23920D01*
X177165Y22627D01*
Y12262D01*
G01X173228Y91141D02*
X173227D01*
X172743Y90657D01*
Y70900D01*
X176493Y67150D01*
Y59560D01*
X174522Y57589D01*
Y23920D01*
X173228Y22626D01*
Y12262D01*
G01X299212D02*
Y34621D01*
X295773Y38060D01*
X281873D01*
X279433Y40500D01*
Y59300D01*
X282333Y62200D01*
X300033D01*
X302233Y64400D01*
Y70519D01*
X297333Y75419D01*
Y81200D01*
X299212Y83079D01*
Y91141D01*
X299213D01*
G01X311023Y83266D02*
X311022D01*
X309488Y84800D01*
X302333D01*
X298433Y80900D01*
Y75800D01*
X304033Y70200D01*
Y64600D01*
X301933Y62500D01*
Y40300D01*
X307533Y34700D01*
X310883D01*
X312733Y32850D01*
Y24900D01*
X311024Y23191D01*
Y12262D01*
G01X334646D02*
Y68287D01*
X331785Y71148D01*
Y80404D01*
X334647Y83266D01*
X334648D01*
G01X322833Y91141D02*
Y72017D01*
X326333Y68517D01*
Y61260D01*
X328303Y59290D01*
Y33370D01*
X322835Y27902D01*
Y12262D01*
G01X330708Y91141D02*
Y70775D01*
X327844Y67911D01*
Y62889D01*
X331546Y59187D01*
Y24013D01*
X330709Y23176D01*
Y12262D01*
G54D12*
X45633Y31600D03*
X38133Y31500D03*
X35363Y37960D03*
X108333Y31600D03*
X100733Y31500D03*
X92533D03*
X84233Y31400D03*
X77233Y31700D03*
X68633Y31400D03*
X60633Y31500D03*
X52733Y31400D03*
X163733Y31500D03*
X155433Y31600D03*
X147833Y31500D03*
X139733D03*
X132333Y31600D03*
X124233D03*
X116233Y31500D03*
X226933D03*
X219033Y31600D03*
X210633Y31500D03*
X202433Y31400D03*
X194933Y31600D03*
X188976Y31543D03*
X179133Y31600D03*
X171333D03*
X288533Y31020D03*
X280933Y31400D03*
X274433D03*
X266033Y31020D03*
X258233Y31300D03*
X249533Y31400D03*
X242333Y31600D03*
X234333Y31400D03*
X329633Y31100D03*
X338583Y32050D03*
X295275Y31658D03*
G54D13*
X30680Y42700D03*
X23720Y37880D03*
X30833Y58700D03*
X21533Y59100D03*
X17033Y53450D03*
X15633Y69500D03*
X25733Y53450D03*
X15333Y62700D03*
X343019Y32504D03*
X347544Y32400D03*
X344360Y43670D03*
X343700Y53890D03*
X340080Y47960D03*
X340010Y58570D03*
X354650Y89890D03*
X355770Y78680D03*
X357350Y72160D03*
G54D14*
X16538Y78346D03*
X8950Y97440D03*
X8750Y50860D03*
X-2462Y651994D03*
X304528Y78346D03*
X364570Y96910D03*
X758452Y17317D03*
X755722Y677788D03*
G54D15*
X47243Y65551D03*
X43308Y73426D03*
X39373Y65551D03*
X35433Y73426D03*
X31498Y65551D03*
X27558Y73426D03*
X23623Y65551D03*
X47243Y91141D03*
X43308Y83266D03*
X39373Y91141D03*
X35433Y83266D03*
X31498Y91141D03*
X27558Y83266D03*
X23623Y91141D03*
X110238Y65551D03*
X106298Y73426D03*
X102363Y65551D03*
X98428Y73426D03*
X94488Y65551D03*
X90553Y73426D03*
X86613Y65551D03*
X82678Y73426D03*
X78743Y65551D03*
X74803Y73426D03*
X70868Y65551D03*
X66928Y73426D03*
X62993Y65551D03*
X59058Y73426D03*
X55118Y65551D03*
X51183Y73426D03*
X110238Y91141D03*
X106298Y83266D03*
X102363Y91141D03*
X98428Y83266D03*
X94488Y91141D03*
X90553Y83266D03*
X86613Y91141D03*
X82678Y83266D03*
X78743Y91141D03*
X74803Y83266D03*
X70868Y91141D03*
X66928Y83266D03*
X62993Y91141D03*
X59058Y83266D03*
X55118Y91141D03*
X51183Y83266D03*
X169293Y73426D03*
X165353Y65551D03*
X161418Y73426D03*
X157483Y65551D03*
X153543Y73426D03*
X149608Y65551D03*
X145668Y73426D03*
X141733Y65551D03*
X137798Y73426D03*
X133858Y65551D03*
X129923Y73426D03*
X125983Y65551D03*
X122048Y73426D03*
X118113Y65551D03*
X114173Y73426D03*
X169293Y83266D03*
X165353Y91141D03*
X161418Y83266D03*
X157483Y91141D03*
X153543Y83266D03*
X149608Y91141D03*
X145668Y83266D03*
X141733Y91141D03*
X137798Y83266D03*
X133858Y91141D03*
X129923Y83266D03*
X125983Y91141D03*
X122048Y83266D03*
X118113Y91141D03*
X114173Y83266D03*
X232283Y73426D03*
X228348Y65551D03*
X224408Y73426D03*
X220473Y65551D03*
X216538Y73426D03*
X212598Y65551D03*
X208663Y73426D03*
X204723Y65551D03*
X200788Y73426D03*
X196853Y65551D03*
X192913Y73426D03*
X188978Y65551D03*
X185038Y73426D03*
X181103Y65551D03*
X177168Y73426D03*
X173228Y65551D03*
X232283Y83266D03*
X228348Y91141D03*
X224408Y83266D03*
X220473Y91141D03*
X216538Y83266D03*
X212598Y91141D03*
X208663Y83266D03*
X204723Y91141D03*
X200788Y83266D03*
X196853Y91141D03*
X192913Y83266D03*
X188978Y91141D03*
X185038Y83266D03*
X181103Y91141D03*
X177168Y83266D03*
X173228Y91141D03*
X291338Y65551D03*
X287403Y73426D03*
X283463Y65551D03*
X279528Y73426D03*
X275593Y65551D03*
X271653Y73426D03*
X267718Y65551D03*
X263778Y73426D03*
X259843Y65551D03*
X255908Y73426D03*
X251968Y65551D03*
X248033Y73426D03*
X244093Y65551D03*
X240158Y73426D03*
X236223Y65551D03*
X291338Y91141D03*
X287403Y83266D03*
X283463Y91141D03*
X279528Y83266D03*
X275593Y91141D03*
X271653Y83266D03*
X267718Y91141D03*
X263778Y83266D03*
X259843Y91141D03*
X255908Y83266D03*
X251968Y91141D03*
X248033Y83266D03*
X244093Y91141D03*
X240158Y83266D03*
X236223Y91141D03*
X350393Y73426D03*
X346458Y65551D03*
X342518Y73426D03*
X338583Y65551D03*
X334648Y73426D03*
X330708Y65551D03*
X326773Y73426D03*
X322833Y65551D03*
X318898Y73426D03*
X314963Y65551D03*
X311023Y73426D03*
X299213Y65551D03*
X295278Y73426D03*
X350393Y83266D03*
X346458Y91141D03*
X342518Y83266D03*
X338583Y91141D03*
X334648Y83266D03*
X330708Y91141D03*
X326773Y83266D03*
X322833Y91141D03*
X318898Y83266D03*
X314963Y91141D03*
X311023Y83266D03*
X299213Y91141D03*
X295278Y83266D03*
G54D16*
G01X-67189Y-77263D02*
G02I-12000J0D01*
G01X-72339D02*
G02I-6850J0D01*
G01X-79189Y-93263D02*
Y-61263D01*
G01X-63189Y-77263D02*
X-95189D01*
G01X-63189Y-93263D02*
Y-173263D01*
G01D02*
X1156611D01*
G01X-63189Y-93263D02*
X1156611D01*
G01X-63189Y-128763D02*
X1156611D01*
G01X43307Y12262D02*
Y29274D01*
X45633Y31600D01*
G01X39370Y12262D02*
Y30263D01*
X38133Y31500D01*
G01X27559Y15712D02*
Y25026D01*
X30248Y27715D01*
Y35035D01*
G01D02*
X23622Y28409D01*
Y12262D01*
G01X35363Y37960D02*
X33173D01*
X30248Y35035D01*
G01X23623Y61999D02*
Y65551D01*
G01D02*
Y69103D01*
G01X20071Y65551D02*
X23623D01*
G01D02*
X27175D01*
G01X27558Y69874D02*
Y73426D01*
G01D02*
Y76978D01*
G01X24006Y73426D02*
X27558D01*
G01X106299Y12262D02*
Y29566D01*
X108333Y31600D01*
G01X102362Y12262D02*
Y29871D01*
X100733Y31500D01*
G01X90551Y12262D02*
Y29518D01*
X92533Y31500D01*
G01X86614Y12262D02*
Y29019D01*
X84233Y31400D01*
G01X74803Y12262D02*
Y29270D01*
X77233Y31700D01*
G01X70866Y12262D02*
Y29167D01*
X68633Y31400D01*
G01X59055Y12262D02*
Y29922D01*
X60633Y31500D01*
G01X55118Y12262D02*
Y29015D01*
X52733Y31400D01*
G01X169291Y12262D02*
Y29558D01*
X171333Y31600D01*
G01X165354Y12262D02*
Y29879D01*
X163733Y31500D01*
G01X153543Y12262D02*
Y29710D01*
X155433Y31600D01*
G01X149606Y12262D02*
Y29727D01*
X147833Y31500D01*
G01X137795Y12262D02*
Y29562D01*
X139733Y31500D01*
G01X133858Y12262D02*
Y30075D01*
X132333Y31600D01*
G01X122047Y12262D02*
Y29414D01*
X124233Y31600D01*
G01X118110Y12262D02*
Y29623D01*
X116233Y31500D01*
G01X228346Y12262D02*
Y30087D01*
X226933Y31500D01*
G01X216535Y12262D02*
Y29102D01*
X219033Y31600D01*
G01X212598Y12262D02*
Y29535D01*
X210633Y31500D01*
G01X200787Y12262D02*
Y29754D01*
X202433Y31400D01*
G01X196850Y12262D02*
Y29683D01*
X194933Y31600D01*
G01X185039Y12262D02*
Y27606D01*
X188976Y31543D01*
G01X181102Y12262D02*
Y29631D01*
X179133Y31600D01*
G01X279527Y15712D02*
Y29994D01*
X280933Y31400D01*
G01X275590Y12262D02*
Y30243D01*
X274433Y31400D01*
G01X259842Y12262D02*
Y29691D01*
X258233Y31300D01*
G01X248031Y12262D02*
Y29898D01*
X249533Y31400D01*
G01X244094Y12262D02*
Y29839D01*
X242333Y31600D01*
G01X232283Y12262D02*
Y29350D01*
X234333Y31400D01*
G01X291338Y12262D02*
Y28215D01*
X288533Y31020D01*
G01X263779Y12262D02*
Y28766D01*
X266033Y31020D01*
G01X326772Y12262D02*
Y28239D01*
X329633Y31100D01*
G01X338583Y12262D02*
Y32050D01*
G01X295275Y12262D02*
Y31658D01*
G01X342518Y79714D02*
Y83266D01*
G01D02*
Y86818D01*
G01X338966Y83266D02*
X342518D01*
G01D02*
X346070D01*
G01X346458Y87589D02*
Y91141D01*
G01D02*
Y94693D01*
G01X342906Y91141D02*
X346458D01*
G01D02*
X350010D01*
G01X350393Y79714D02*
Y83266D01*
G01D02*
Y86818D01*
G01X346841Y83266D02*
X350393D01*
G01D02*
X353945D01*
G01X342518Y69874D02*
Y73426D01*
G01D02*
Y76978D01*
G01X338966Y73426D02*
X342518D01*
G01D02*
X346070D01*
G01X346458Y61999D02*
Y65551D01*
G01D02*
Y69103D01*
G01X342906Y65551D02*
X346458D01*
G01D02*
X350010D01*
G01X369111Y-93263D02*
Y-173263D01*
G01X506611Y-93263D02*
Y-173263D01*
G01X621611Y-93263D02*
Y-173263D01*
G01X789111Y-93263D02*
Y-173263D01*
G01X959111Y-93263D02*
Y-173263D01*
G01X1156611Y-93263D02*
Y-173263D01*
G01X1184611Y-77263D02*
G02I-12000J0D01*
G01X1179461D02*
G02I-6850J0D01*
G01X1172611Y-93263D02*
Y-61263D01*
G01X1188611Y-77263D02*
X1156611D01*
G54D17*
G01X346457Y27500D02*
Y12262D01*
G01X342520D02*
Y28887D01*
G01X347544Y32400D02*
X350394Y29550D01*
Y12262D01*
G54D18*
G01X188978Y91141D02*
X188977D01*
X188553Y90717D01*
Y70728D01*
X192253Y67028D01*
Y59992D01*
X191533Y59272D01*
Y26900D01*
X188976Y24343D01*
Y12262D01*
G54D19*
G01X-44374Y-163263D02*
Y-145763D01*
G01X-35204D02*
Y-163263D01*
G01Y-154513D02*
X-44374D01*
G01X-22289Y-163263D02*
X-23599Y-162971D01*
X-24909Y-161805D01*
X-25783Y-159763D01*
X-26219Y-157430D01*
X-25783Y-155096D01*
X-24909Y-153055D01*
X-23599Y-151888D01*
X-22289Y-151597D01*
X-20979Y-151888D01*
X-19669Y-153055D01*
X-18796Y-155096D01*
X-18577Y-157430D01*
X-18796Y-159763D01*
X-19669Y-161805D01*
X-20979Y-162971D01*
X-22289Y-163263D01*
G01X-8501D02*
Y-151597D01*
G01Y-154513D02*
X-7627Y-153055D01*
X-6317Y-151888D01*
X-4571Y-151597D01*
X-3043Y-151888D01*
X-1732Y-153055D01*
X-1077Y-155096D01*
Y-163263D01*
G01X9436Y-155388D02*
X16423D01*
X15768Y-153346D01*
X14676Y-152180D01*
X13148Y-151597D01*
X11619Y-151888D01*
X10309Y-152763D01*
X9436Y-154805D01*
X8999Y-156555D01*
Y-158305D01*
X9436Y-160055D01*
X10528Y-161805D01*
X11838Y-162971D01*
X13366Y-163263D01*
X14894Y-162680D01*
X16423Y-160930D01*
G01X25626Y-168513D02*
X26936Y-169096D01*
X28683Y-168513D01*
X29774Y-167347D01*
X30648Y-165888D01*
X31957Y-161222D01*
X34796Y-151597D01*
G01X27809D02*
X31957Y-161222D01*
G01X66957Y-153930D02*
X67831Y-153055D01*
X68486Y-151597D01*
X68923Y-149554D01*
X68486Y-147805D01*
X67613Y-146638D01*
X66084Y-145763D01*
X60189D01*
Y-163263D01*
X67394D01*
X68923Y-162097D01*
X69796Y-160346D01*
X70233Y-158305D01*
X69796Y-156263D01*
X68486Y-154513D01*
X66957Y-153930D01*
X60189D01*
G01X86641Y-163263D02*
Y-151597D01*
G01Y-153638D02*
X85768Y-152472D01*
X84457Y-151888D01*
X82929Y-151597D01*
X81401Y-152180D01*
X80091Y-153346D01*
X79217Y-155096D01*
X78781Y-157430D01*
X79217Y-159763D01*
X80091Y-161513D01*
X81401Y-162680D01*
X82929Y-163263D01*
X84457Y-162971D01*
X85768Y-162097D01*
X86641Y-160930D01*
G01X104141Y-145763D02*
Y-163263D01*
G01Y-160639D02*
X103268Y-162097D01*
X101957Y-162971D01*
X100429Y-163263D01*
X98683Y-162680D01*
X97373Y-161222D01*
X96499Y-159472D01*
X96281Y-157430D01*
X96499Y-155388D01*
X97373Y-153638D01*
X98683Y-152180D01*
X100429Y-151597D01*
X101957Y-151888D01*
X103049Y-152472D01*
X104141Y-153638D01*
G01X114654Y-167638D02*
X116183Y-168805D01*
X117929Y-169096D01*
X119457Y-168805D01*
X120768Y-167347D01*
X121641Y-165305D01*
Y-151597D01*
G01Y-153930D02*
X120768Y-152763D01*
X119457Y-151888D01*
X117929Y-151597D01*
X116183Y-152180D01*
X115091Y-153346D01*
X114217Y-155388D01*
X113781Y-157430D01*
X113999Y-159180D01*
X114873Y-161222D01*
X116183Y-162680D01*
X117929Y-163263D01*
X119239Y-162971D01*
X120768Y-161805D01*
X121641Y-160639D01*
G01X131936Y-155388D02*
X138923D01*
X138268Y-153346D01*
X137176Y-152180D01*
X135648Y-151597D01*
X134119Y-151888D01*
X132809Y-152763D01*
X131936Y-154805D01*
X131499Y-156555D01*
Y-158305D01*
X131936Y-160055D01*
X133028Y-161805D01*
X134338Y-162971D01*
X135866Y-163263D01*
X137394Y-162680D01*
X138923Y-160930D01*
G01X149654Y-163263D02*
Y-151597D01*
G01Y-153930D02*
X150746Y-152763D01*
X151838Y-151888D01*
X153366Y-151597D01*
X154457Y-151888D01*
X155768Y-152763D01*
G01X183344Y-163263D02*
Y-145763D01*
X188803D01*
X190549Y-146638D01*
X191641Y-147805D01*
X192078Y-150138D01*
X191641Y-152472D01*
X190331Y-153930D01*
X188803Y-154805D01*
X183344D01*
G01X188803D02*
X192078Y-163263D01*
G01X205211Y-151597D02*
Y-163263D01*
G01Y-146930D02*
X204774Y-146638D01*
Y-146055D01*
X205211Y-145763D01*
X205648Y-146055D01*
Y-146638D01*
X205211Y-146930D01*
G01X219436Y-161222D02*
X220528Y-162388D01*
X222056Y-163263D01*
X223366D01*
X224676Y-162680D01*
X225549Y-161805D01*
X225986Y-160639D01*
X225768Y-158888D01*
X224894Y-158013D01*
X220964Y-156263D01*
X220091Y-154221D01*
X220528Y-152763D01*
X221401Y-151888D01*
X222711Y-151597D01*
X224021Y-151888D01*
X225331Y-152763D01*
G01X236936Y-155388D02*
X243923D01*
X243268Y-153346D01*
X242176Y-152180D01*
X240648Y-151597D01*
X239119Y-151888D01*
X237809Y-152763D01*
X236936Y-154805D01*
X236499Y-156555D01*
Y-158305D01*
X236936Y-160055D01*
X238028Y-161805D01*
X239338Y-162971D01*
X240866Y-163263D01*
X242394Y-162680D01*
X243923Y-160930D01*
G01X254654Y-163263D02*
Y-151597D01*
G01Y-153930D02*
X255746Y-152763D01*
X256838Y-151888D01*
X258366Y-151597D01*
X259457Y-151888D01*
X260768Y-152763D01*
G01X297514Y-147222D02*
X296204Y-146346D01*
X294676Y-145763D01*
X292929D01*
X290964Y-146638D01*
X289436Y-148096D01*
X288344Y-149847D01*
X287471Y-152763D01*
X287252Y-155388D01*
X287689Y-158013D01*
X288344Y-159763D01*
X289654Y-161513D01*
X291183Y-162680D01*
X292711Y-163263D01*
X294239D01*
X295768Y-162680D01*
X297078Y-161805D01*
X298170Y-160639D01*
G01X314141Y-163263D02*
Y-151597D01*
G01Y-153638D02*
X313268Y-152472D01*
X311957Y-151888D01*
X310429Y-151597D01*
X308901Y-152180D01*
X307591Y-153346D01*
X306717Y-155096D01*
X306281Y-157430D01*
X306717Y-159763D01*
X307591Y-161513D01*
X308901Y-162680D01*
X310429Y-163263D01*
X311957Y-162971D01*
X313268Y-162097D01*
X314141Y-160930D01*
G01X324654Y-163263D02*
Y-151597D01*
G01Y-153930D02*
X325746Y-152763D01*
X326838Y-151888D01*
X328366Y-151597D01*
X329457Y-151888D01*
X330768Y-152763D01*
G01X349141Y-145763D02*
Y-163263D01*
G01Y-160639D02*
X348268Y-162097D01*
X346957Y-162971D01*
X345429Y-163263D01*
X343683Y-162680D01*
X342373Y-161222D01*
X341499Y-159472D01*
X341281Y-157430D01*
X341499Y-155388D01*
X342373Y-153638D01*
X343683Y-152180D01*
X345429Y-151597D01*
X346957Y-151888D01*
X348049Y-152472D01*
X349141Y-153638D01*
G01X112034Y-118263D02*
Y-100763D01*
X117711Y-115346D01*
X123388Y-100763D01*
Y-118263D01*
G01X135211D02*
X133901Y-117971D01*
X132591Y-116805D01*
X131717Y-114763D01*
X131281Y-112430D01*
X131717Y-110096D01*
X132591Y-108055D01*
X133901Y-106888D01*
X135211Y-106597D01*
X136521Y-106888D01*
X137831Y-108055D01*
X138704Y-110096D01*
X138923Y-112430D01*
X138704Y-114763D01*
X137831Y-116805D01*
X136521Y-117971D01*
X135211Y-118263D01*
G01X156641Y-100763D02*
Y-118263D01*
G01Y-115639D02*
X155768Y-117097D01*
X154457Y-117971D01*
X152929Y-118263D01*
X151183Y-117680D01*
X149873Y-116222D01*
X148999Y-114472D01*
X148781Y-112430D01*
X148999Y-110388D01*
X149873Y-108638D01*
X151183Y-107180D01*
X152929Y-106597D01*
X154457Y-106888D01*
X155549Y-107472D01*
X156641Y-108638D01*
G01X166936Y-110388D02*
X173923D01*
X173268Y-108346D01*
X172176Y-107180D01*
X170648Y-106597D01*
X169119Y-106888D01*
X167809Y-107763D01*
X166936Y-109805D01*
X166499Y-111555D01*
Y-113305D01*
X166936Y-115055D01*
X168028Y-116805D01*
X169338Y-117971D01*
X170866Y-118263D01*
X172394Y-117680D01*
X173923Y-115930D01*
G01X187711Y-118263D02*
Y-100763D01*
G01X402811Y-163263D02*
Y-145763D01*
X400191Y-149263D01*
G01Y-163263D02*
X405431D01*
G01X415508Y-159763D02*
X416817Y-161805D01*
X418564Y-162971D01*
X420529Y-163263D01*
X422276Y-162971D01*
X424023Y-161513D01*
X425114Y-159763D01*
X425333Y-158013D01*
X424896Y-155972D01*
X423368Y-154513D01*
X421839Y-153930D01*
X419874D01*
G01X421839D02*
X423149Y-153055D01*
X424241Y-151597D01*
X424678Y-149847D01*
X424241Y-148096D01*
X423149Y-146638D01*
X421184Y-145763D01*
X419219Y-146055D01*
X417254Y-147222D01*
G01X434099Y-161222D02*
X435628Y-162680D01*
X437374Y-163263D01*
X439121Y-162680D01*
X440649Y-160930D01*
X441741Y-158305D01*
X442178Y-155680D01*
Y-152472D01*
X441741Y-149847D01*
X440649Y-147513D01*
X439339Y-146346D01*
X437811Y-145763D01*
X436064Y-146346D01*
X434754Y-147513D01*
X433881Y-149263D01*
X433444Y-151597D01*
X433881Y-153638D01*
X434973Y-155680D01*
X436283Y-156847D01*
X437811Y-157138D01*
X439557Y-156555D01*
X440868Y-155096D01*
X442178Y-152472D01*
G01X455311Y-163263D02*
Y-145763D01*
X452691Y-149263D01*
G01Y-163263D02*
X457931D01*
G01X469099Y-161222D02*
X470628Y-162680D01*
X472374Y-163263D01*
X474121Y-162680D01*
X475649Y-160930D01*
X476741Y-158305D01*
X477178Y-155680D01*
Y-152472D01*
X476741Y-149847D01*
X475649Y-147513D01*
X474339Y-146346D01*
X472811Y-145763D01*
X471064Y-146346D01*
X469754Y-147513D01*
X468881Y-149263D01*
X468444Y-151597D01*
X468881Y-153638D01*
X469973Y-155680D01*
X471283Y-156847D01*
X472811Y-157138D01*
X474557Y-156555D01*
X475868Y-155096D01*
X477178Y-152472D01*
G01X389694Y-118263D02*
Y-100763D01*
X394934D01*
X396681Y-101638D01*
X397991Y-103680D01*
X398428Y-106013D01*
X397991Y-108346D01*
X396899Y-110096D01*
X394934Y-110972D01*
X389694D01*
G01X416364Y-102222D02*
X415054Y-101346D01*
X413526Y-100763D01*
X411779D01*
X409814Y-101638D01*
X408286Y-103096D01*
X407194Y-104847D01*
X406321Y-107763D01*
X406102Y-110388D01*
X406539Y-113013D01*
X407194Y-114763D01*
X408504Y-116513D01*
X410033Y-117680D01*
X411561Y-118263D01*
X413089D01*
X414618Y-117680D01*
X415928Y-116805D01*
X417020Y-115639D01*
G01X430807Y-108930D02*
X431681Y-108055D01*
X432336Y-106597D01*
X432773Y-104554D01*
X432336Y-102805D01*
X431463Y-101638D01*
X429934Y-100763D01*
X424039D01*
Y-118263D01*
X431244D01*
X432773Y-117097D01*
X433646Y-115346D01*
X434083Y-113305D01*
X433646Y-111263D01*
X432336Y-109513D01*
X430807Y-108930D01*
X424039D01*
G01X440011Y-124096D02*
X453111D01*
G01X459039Y-118263D02*
Y-100763D01*
X469083Y-118263D01*
Y-100763D01*
G01X481561Y-118263D02*
X479814Y-117971D01*
X478286Y-116805D01*
X476976Y-115055D01*
X476102Y-113013D01*
X475666Y-110680D01*
Y-108346D01*
X476102Y-106013D01*
X476976Y-103971D01*
X478286Y-102222D01*
X479814Y-101055D01*
X481561Y-100763D01*
X483307Y-101055D01*
X484836Y-102222D01*
X486146Y-103971D01*
X487020Y-106013D01*
X487456Y-108346D01*
Y-110680D01*
X487020Y-113013D01*
X486146Y-115055D01*
X484836Y-116805D01*
X483307Y-117971D01*
X481561Y-118263D01*
G01X532402Y-100763D02*
X537861Y-118263D01*
X543320Y-100763D01*
G01X559728Y-118263D02*
X550994D01*
Y-100763D01*
X559728D01*
G01X556234Y-109221D02*
X550994D01*
G01X568494Y-118263D02*
Y-100763D01*
X573953D01*
X575699Y-101638D01*
X576791Y-102805D01*
X577228Y-105138D01*
X576791Y-107472D01*
X575481Y-108930D01*
X573953Y-109805D01*
X568494D01*
G01X573953D02*
X577228Y-118263D01*
G01X590361Y-118846D02*
X589924Y-118555D01*
Y-117971D01*
X590361Y-117680D01*
X590798Y-117971D01*
Y-118555D01*
X590361Y-118846D01*
G01X550776Y-160930D02*
X552523Y-162388D01*
X554488Y-163263D01*
X556234D01*
X557981Y-162388D01*
X559291Y-160930D01*
X559946Y-158888D01*
X559509Y-156847D01*
X558418Y-155096D01*
X556453Y-153930D01*
X553833Y-153346D01*
X552304Y-152180D01*
X551649Y-150138D01*
X552086Y-148096D01*
X553178Y-146638D01*
X554706Y-145763D01*
X556234D01*
X557763Y-146346D01*
X559073Y-147805D01*
G01X567402Y-163263D02*
X572861Y-145763D01*
X578320Y-163263D01*
G01X576354Y-157138D02*
X569367D01*
G01X718428Y-145763D02*
Y-163263D01*
X709694D01*
G01X693941D02*
Y-145763D01*
X702020Y-158305D01*
X691102D01*
G01X665944Y-100763D02*
Y-118263D01*
X674678D01*
G01X691741D02*
Y-106597D01*
G01Y-108638D02*
X690868Y-107472D01*
X689557Y-106888D01*
X688029Y-106597D01*
X686501Y-107180D01*
X685191Y-108346D01*
X684317Y-110096D01*
X683881Y-112430D01*
X684317Y-114763D01*
X685191Y-116513D01*
X686501Y-117680D01*
X688029Y-118263D01*
X689557Y-117971D01*
X690868Y-117097D01*
X691741Y-115930D01*
G01X700726Y-123513D02*
X702036Y-124096D01*
X703783Y-123513D01*
X704874Y-122347D01*
X705748Y-120888D01*
X707057Y-116222D01*
X709896Y-106597D01*
G01X702909D02*
X707057Y-116222D01*
G01X719536Y-110388D02*
X726523D01*
X725868Y-108346D01*
X724776Y-107180D01*
X723248Y-106597D01*
X721719Y-106888D01*
X720409Y-107763D01*
X719536Y-109805D01*
X719099Y-111555D01*
Y-113305D01*
X719536Y-115055D01*
X720628Y-116805D01*
X721938Y-117971D01*
X723466Y-118263D01*
X724994Y-117680D01*
X726523Y-115930D01*
G01X737254Y-118263D02*
Y-106597D01*
G01Y-108930D02*
X738346Y-107763D01*
X739438Y-106888D01*
X740966Y-106597D01*
X742057Y-106888D01*
X743368Y-107763D01*
G01X808058Y-118263D02*
Y-100763D01*
X812424D01*
X814171Y-101638D01*
X815481Y-102805D01*
X816573Y-104554D01*
X817446Y-106597D01*
X817664Y-109513D01*
X817446Y-112430D01*
X816573Y-114472D01*
X815481Y-116222D01*
X814171Y-117388D01*
X812424Y-118263D01*
X808058D01*
G01X827086Y-110388D02*
X834073D01*
X833418Y-108346D01*
X832326Y-107180D01*
X830798Y-106597D01*
X829269Y-106888D01*
X827959Y-107763D01*
X827086Y-109805D01*
X826649Y-111555D01*
Y-113305D01*
X827086Y-115055D01*
X828178Y-116805D01*
X829488Y-117971D01*
X831016Y-118263D01*
X832544Y-117680D01*
X834073Y-115930D01*
G01X844586Y-116222D02*
X845678Y-117388D01*
X847206Y-118263D01*
X848516D01*
X849826Y-117680D01*
X850699Y-116805D01*
X851136Y-115639D01*
X850918Y-113888D01*
X850044Y-113013D01*
X846114Y-111263D01*
X845241Y-109221D01*
X845678Y-107763D01*
X846551Y-106888D01*
X847861Y-106597D01*
X849171Y-106888D01*
X850481Y-107763D01*
G01X865361Y-106597D02*
Y-118263D01*
G01Y-101930D02*
X864924Y-101638D01*
Y-101055D01*
X865361Y-100763D01*
X865798Y-101055D01*
Y-101638D01*
X865361Y-101930D01*
G01X879804Y-122638D02*
X881333Y-123805D01*
X883079Y-124096D01*
X884607Y-123805D01*
X885918Y-122347D01*
X886791Y-120305D01*
Y-106597D01*
G01Y-108930D02*
X885918Y-107763D01*
X884607Y-106888D01*
X883079Y-106597D01*
X881333Y-107180D01*
X880241Y-108346D01*
X879367Y-110388D01*
X878931Y-112430D01*
X879149Y-114180D01*
X880023Y-116222D01*
X881333Y-117680D01*
X883079Y-118263D01*
X884389Y-117971D01*
X885918Y-116805D01*
X886791Y-115639D01*
G01X896649Y-118263D02*
Y-106597D01*
G01Y-109513D02*
X897523Y-108055D01*
X898833Y-106888D01*
X900579Y-106597D01*
X902107Y-106888D01*
X903418Y-108055D01*
X904073Y-110096D01*
Y-118263D01*
G01X914586Y-110388D02*
X921573D01*
X920918Y-108346D01*
X919826Y-107180D01*
X918298Y-106597D01*
X916769Y-106888D01*
X915459Y-107763D01*
X914586Y-109805D01*
X914149Y-111555D01*
Y-113305D01*
X914586Y-115055D01*
X915678Y-116805D01*
X916988Y-117971D01*
X918516Y-118263D01*
X920044Y-117680D01*
X921573Y-115930D01*
G01X932304Y-118263D02*
Y-106597D01*
G01Y-108930D02*
X933396Y-107763D01*
X934488Y-106888D01*
X936016Y-106597D01*
X937107Y-106888D01*
X938418Y-107763D01*
G01X853991Y-145763D02*
X859231D01*
G01X856611D02*
Y-163263D01*
G01X853991D02*
X859231D01*
G01X868652Y-145763D02*
X874111Y-163263D01*
X879570Y-145763D01*
G01X891611Y-163263D02*
Y-155388D01*
X887244Y-145763D01*
G01X895978D02*
X891611Y-155388D01*
G01X979061Y-163263D02*
Y-145763D01*
X976441Y-149263D01*
G01Y-163263D02*
X981681D01*
G01X996561D02*
Y-145763D01*
X993941Y-149263D01*
G01Y-163263D02*
X999181D01*
G01X1010131Y-163846D02*
X1017991Y-145763D01*
G01X1027413Y-148680D02*
X1028723Y-146930D01*
X1030251Y-146055D01*
X1031998Y-145763D01*
X1034181Y-146346D01*
X1035709Y-147805D01*
X1036146Y-149554D01*
X1035928Y-151305D01*
X1035054Y-152763D01*
X1030688Y-155680D01*
X1028723Y-157721D01*
X1027413Y-160639D01*
X1026976Y-163263D01*
X1036146D01*
G01X1044913Y-148680D02*
X1046223Y-146930D01*
X1047751Y-146055D01*
X1049498Y-145763D01*
X1051681Y-146346D01*
X1053209Y-147805D01*
X1053646Y-149554D01*
X1053428Y-151305D01*
X1052554Y-152763D01*
X1048188Y-155680D01*
X1046223Y-157721D01*
X1044913Y-160639D01*
X1044476Y-163263D01*
X1053646D01*
G01X1062631Y-163846D02*
X1070491Y-145763D01*
G01X1079913Y-148680D02*
X1081223Y-146930D01*
X1082751Y-146055D01*
X1084498Y-145763D01*
X1086681Y-146346D01*
X1088209Y-147805D01*
X1088646Y-149554D01*
X1088428Y-151305D01*
X1087554Y-152763D01*
X1083188Y-155680D01*
X1081223Y-157721D01*
X1079913Y-160639D01*
X1079476Y-163263D01*
X1088646D01*
G01X1101561Y-145763D02*
X1099814Y-146346D01*
X1098504Y-147805D01*
X1097631Y-149554D01*
X1096976Y-151888D01*
X1096758Y-154513D01*
X1096976Y-157138D01*
X1097631Y-159472D01*
X1098504Y-161222D01*
X1099814Y-162680D01*
X1101561Y-163263D01*
X1103307Y-162680D01*
X1104618Y-161222D01*
X1105491Y-159472D01*
X1106146Y-157138D01*
X1106364Y-154513D01*
X1106146Y-151888D01*
X1105491Y-149554D01*
X1104618Y-147805D01*
X1103307Y-146346D01*
X1101561Y-145763D01*
G01X1119061Y-163263D02*
Y-145763D01*
X1116441Y-149263D01*
G01Y-163263D02*
X1121681D01*
G01X1131758Y-159763D02*
X1133067Y-161805D01*
X1134814Y-162971D01*
X1136779Y-163263D01*
X1138526Y-162971D01*
X1140273Y-161513D01*
X1141364Y-159763D01*
X1141583Y-158013D01*
X1141146Y-155972D01*
X1139618Y-154513D01*
X1138089Y-153930D01*
X1136124D01*
G01X1138089D02*
X1139399Y-153055D01*
X1140491Y-151597D01*
X1140928Y-149847D01*
X1140491Y-148096D01*
X1139399Y-146638D01*
X1137434Y-145763D01*
X1135469Y-146055D01*
X1133504Y-147222D01*
G01X1026758Y-118263D02*
Y-100763D01*
X1031124D01*
X1032871Y-101638D01*
X1034181Y-102805D01*
X1035273Y-104554D01*
X1036146Y-106597D01*
X1036364Y-109513D01*
X1036146Y-112430D01*
X1035273Y-114472D01*
X1034181Y-116222D01*
X1032871Y-117388D01*
X1031124Y-118263D01*
X1026758D01*
G01X1052991D02*
Y-106597D01*
G01Y-108638D02*
X1052118Y-107472D01*
X1050807Y-106888D01*
X1049279Y-106597D01*
X1047751Y-107180D01*
X1046441Y-108346D01*
X1045567Y-110096D01*
X1045131Y-112430D01*
X1045567Y-114763D01*
X1046441Y-116513D01*
X1047751Y-117680D01*
X1049279Y-118263D01*
X1050807Y-117971D01*
X1052118Y-117097D01*
X1052991Y-115930D01*
G01X1066561Y-100763D02*
Y-118263D01*
G01X1063504Y-106597D02*
X1069618D01*
G01X1080786Y-110388D02*
X1087773D01*
X1087118Y-108346D01*
X1086026Y-107180D01*
X1084498Y-106597D01*
X1082969Y-106888D01*
X1081659Y-107763D01*
X1080786Y-109805D01*
X1080349Y-111555D01*
Y-113305D01*
X1080786Y-115055D01*
X1081878Y-116805D01*
X1083188Y-117971D01*
X1084716Y-118263D01*
X1086244Y-117680D01*
X1087773Y-115930D01*
M02*
